(kicad_pcb
	(version 20241229)
	(generator "pcbnew")
	(generator_version "9.0")
	(general
		(thickness 1.6642)
		(legacy_teardrops no)
	)
	(paper "A3")
	(title_block
		(title "PolarFire SoM")
		(date "2025-07-22")
		(rev "1.1.4")
		(company "Antmicro Ltd")
		(comment 1 "www.antmicro.com")
		(comment 9 "footprints 115-117 of 470")
	)
	(layers
		(0 "F.Cu" mixed)
		(4 "In1.Cu" power)
		(6 "In2.Cu" signal)
		(8 "In3.Cu" power)
		(10 "In4.Cu" signal)
		(12 "In5.Cu" power)
		(14 "In6.Cu" power)
		(16 "In7.Cu" signal)
		(18 "In8.Cu" power)
		(20 "In9.Cu" signal)
		(22 "In10.Cu" power)
		(24 "In11.Cu" signal)
		(26 "In12.Cu" signal)
		(2 "B.Cu" mixed)
		(9 "F.Adhes" user "F.Adhesive")
		(11 "B.Adhes" user "B.Adhesive")
		(13 "F.Paste" user)
		(15 "B.Paste" user)
		(5 "F.SilkS" user "F.Silkscreen")
		(7 "B.SilkS" user "B.Silkscreen")
		(1 "F.Mask" user)
		(3 "B.Mask" user)
		(17 "Dwgs.User" user "User.Drawings")
		(19 "Cmts.User" user "User.Comments")
		(21 "Eco1.User" user "User.Eco1")
		(23 "Eco2.User" user "User.Eco2")
		(25 "Edge.Cuts" user)
		(27 "Margin" user)
		(31 "F.CrtYd" user "F.Courtyard")
		(29 "B.CrtYd" user "B.Courtyard")
		(35 "F.Fab" user)
		(33 "B.Fab" user)
	)
	(footprint "antmicro-footprints:L_0805_2012Metric"
		(layer "F.Cu")
		(at 176.9 139.75 90)
		(descr "Inductor  SMD 0805")
		(tags "inductor SMD 0805")
		(property "Reference" "L2"
			(at 1.813695 -0.715 180)
			(layer "F.SilkS")
			(effects
				(font
					(size 0.7 0.7)
					(thickness 0.15)
				)
				(justify left bottom)
			)
		)
		(property "Value" "L_1u_3.2A_0805"
			(at 0 1.947 90)
			(layer "F.Fab")
			(hide yes)
			(effects
				(font
					(size 0.7 0.7)
					(thickness 0.15)
				)
				(justify left bottom)
			)
		)
		(property "Datasheet" "https://abracon.com/datasheets/AOTA-B201208S.pdf"
			(at 0 0 90)
			(layer "F.Fab")
			(hide yes)
			(effects
				(font
					(size 1.27 1.27)
					(thickness 0.15)
				)
			)
		)
		(property "Description" "Power Inductor (SMT), 1 µH, 0.05 ohm, 3.2 A, AOTA-B201208S"
			(at 0 0 90)
			(layer "F.Fab")
			(hide yes)
			(effects
				(font
					(size 1.27 1.27)
					(thickness 0.15)
				)
			)
		)
		(property "Author" "Antmicro"
			(at 316.65 -37.15 0)
			(layer "F.Fab")
			(hide yes)
			(effects
				(font
					(size 1 1)
					(thickness 0.15)
				)
			)
		)
		(property "IMax" "3.2 A"
			(at 316.65 -37.15 0)
			(layer "F.Fab")
			(hide yes)
			(effects
				(font
					(size 1 1)
					(thickness 0.15)
				)
			)
		)
		(property "ISat" "3.5 A"
			(at 316.65 -37.15 0)
			(layer "F.Fab")
			(hide yes)
			(effects
				(font
					(size 1 1)
					(thickness 0.15)
				)
			)
		)
		(property "License" "Apache-2.0"
			(at 316.65 -37.15 0)
			(layer "F.Fab")
			(hide yes)
			(effects
				(font
					(size 1 1)
					(thickness 0.15)
				)
			)
		)
		(property "MPN" "AOTA-B201208S1R0MT "
			(at 316.65 -37.15 0)
			(layer "F.Fab")
			(hide yes)
			(effects
				(font
					(size 1 1)
					(thickness 0.15)
				)
			)
		)
		(property "Manufacturer" "Abracon"
			(at 316.65 -37.15 0)
			(layer "F.Fab")
			(hide yes)
			(effects
				(font
					(size 1 1)
					(thickness 0.15)
				)
			)
		)
		(property "Public" ""
			(at 316.65 -37.15 0)
			(layer "F.Fab")
			(hide yes)
			(effects
				(font
					(size 1 1)
					(thickness 0.15)
				)
			)
		)
		(property "Size" "2x1.2"
			(at 316.65 -37.15 0)
			(layer "F.Fab")
			(hide yes)
			(effects
				(font
					(size 1 1)
					(thickness 0.15)
				)
			)
		)
		(property "Val" "1u/3.2A"
			(at 316.65 -37.15 0)
			(layer "F.Fab")
			(hide yes)
			(effects
				(font
					(size 1 1)
					(thickness 0.15)
				)
			)
		)
		(sheetname "/Supply/")
		(sheetfile "supply.kicad_sch")
		(attr smd)
		(fp_line
			(start -0.3 -0.7)
			(end 0.3 -0.7)
			(stroke
				(width 0.15)
				(type solid)
			)
			(layer "F.SilkS")
		)
		(fp_line
			(start -0.3 0.7)
			(end 0.3 0.7)
			(stroke
				(width 0.15)
				(type solid)
			)
			(layer "F.SilkS")
		)
		(fp_rect
			(start 1.95 -0.9)
			(end -1.95 0.9)
			(stroke
				(width 0.05)
				(type default)
			)
			(fill no)
			(layer "F.CrtYd")
		)
		(fp_rect
			(start -0.95 -0.675)
			(end 0.95 0.675)
			(stroke
				(width 0.15)
				(type solid)
			)
			(fill no)
			(layer "F.Fab")
		)
		(fp_text user "Author: Antmicro"
			(at -1.9 5.947 90)
			(layer "F.Fab")
			(effects
				(font
					(size 0.7 0.7)
					(thickness 0.15)
				)
				(justify left bottom)
			)
		)
		(fp_text user "${REFERENCE}"
			(at -1.9 3.947 90)
			(layer "F.Fab")
			(effects
				(font
					(size 0.7 0.7)
					(thickness 0.15)
				)
				(justify left bottom)
			)
		)
		(fp_text user "License: Apache-2.0"
			(at -1.9 4.947 90)
			(layer "F.Fab")
			(effects
				(font
					(size 0.7 0.7)
					(thickness 0.15)
				)
				(justify left bottom)
			)
		)
		(pad "1" smd roundrect
			(at -1.1 0 90)
			(size 1.2 1.3)
			(layers "F.Cu" "F.Mask" "F.Paste")
			(roundrect_rratio 0.25)
			(net 168 "Net-(U7-SW1)")
			(pintype "passive")
		)
		(pad "2" smd roundrect
			(at 1.1 0 90)
			(size 1.2 1.3)
			(layers "F.Cu" "F.Mask" "F.Paste")
			(roundrect_rratio 0.25)
			(net 209 "/Supply/SENSE1_P")
			(pintype "passive")
		)
	)
	(footprint "antmicro-footprints:TP_SMD_0.75mm"
		(layer "F.Cu")
		(at 212.25 140.425 90)
		(property "Reference" "TP11"
			(at 0 -0.6 90)
			(layer "F.SilkS")
			(hide yes)
			(effects
				(font
					(size 0.7 0.7)
					(thickness 0.15)
				)
				(justify left bottom)
			)
		)
		(property "Value" "TP_0.75mm_SMD"
			(at 0 1.2 90)
			(layer "F.Fab")
			(hide yes)
			(effects
				(font
					(size 0.7 0.7)
					(thickness 0.15)
				)
				(justify left bottom)
			)
		)
		(property "Description" "SMT test point"
			(at 0 0 90)
			(layer "F.Fab")
			(hide yes)
			(effects
				(font
					(size 1.27 1.27)
					(thickness 0.15)
				)
			)
		)
		(property "Author" "Antmicro"
			(at 352.675 -71.825 0)
			(layer "F.Fab")
			(hide yes)
			(effects
				(font
					(size 1 1)
					(thickness 0.15)
				)
			)
		)
		(property "License" "Apache-2.0"
			(at 352.675 -71.825 0)
			(layer "F.Fab")
			(hide yes)
			(effects
				(font
					(size 1 1)
					(thickness 0.15)
				)
			)
		)
		(property "MPN" ""
			(at 352.675 -71.825 0)
			(layer "F.Fab")
			(hide yes)
			(effects
				(font
					(size 1 1)
					(thickness 0.15)
				)
			)
		)
		(property "Manufacturer" ""
			(at 352.675 -71.825 0)
			(layer "F.Fab")
			(hide yes)
			(effects
				(font
					(size 1 1)
					(thickness 0.15)
				)
			)
		)
		(property "Public" "False"
			(at 352.675 -71.825 0)
			(layer "F.Fab")
			(hide yes)
			(effects
				(font
					(size 1 1)
					(thickness 0.15)
				)
			)
		)
		(sheetname "/USB/")
		(sheetfile "usb.kicad_sch")
		(attr exclude_from_pos_files exclude_from_bom)
		(fp_circle
			(center 0 0)
			(end 0.475 0)
			(stroke
				(width 0.05)
				(type default)
			)
			(fill no)
			(layer "F.CrtYd")
		)
		(fp_text user "Author: Antmicro"
			(at -0.4 3.901 90)
			(layer "F.Fab")
			(effects
				(font
					(size 0.7 0.7)
					(thickness 0.15)
				)
				(justify left bottom)
			)
		)
		(fp_text user "License: Apache-2.0"
			(at -0.4 5.101 90)
			(layer "F.Fab")
			(effects
				(font
					(size 0.7 0.7)
					(thickness 0.15)
				)
				(justify left bottom)
			)
		)
		(fp_text user "${REFERENCE}"
			(at -0.4 2.7 90)
			(layer "F.Fab")
			(effects
				(font
					(size 0.7 0.7)
					(thickness 0.15)
				)
				(justify left bottom)
			)
		)
		(pad "1" smd circle
			(at 0 0 90)
			(size 0.75 0.75)
			(layers "F.Cu" "F.Mask")
			(net 221 "VBUS")
			(pinfunction "1")
			(pintype "passive")
		)
	)
	(footprint "antmicro-footprints:C_0402_1005Metric"
		(layer "F.Cu")
		(at 218.21 154.14 180)
		(descr "Capacitor SMD 0402")
		(tags "capacitor SMD 0402")
		(property "Reference" "C68"
			(at 2.86 -0.36 0)
			(layer "F.SilkS")
			(effects
				(font
					(size 0.7 0.7)
					(thickness 0.15)
				)
				(justify right bottom)
			)
		)
		(property "Value" "C_100n_0402"
			(at -1.022927 2.155213 0)
			(layer "F.Fab")
			(hide yes)
			(effects
				(font
					(size 0.7 0.7)
					(thickness 0.15)
				)
				(justify right bottom)
			)
		)
		(property "Datasheet" "https://www.murata.com/products/productdetail?partno=GRM155R61H104KE14%23"
			(at 0 0 180)
			(layer "F.Fab")
			(hide yes)
			(effects
				(font
					(size 1.27 1.27)
					(thickness 0.15)
				)
			)
		)
		(property "Description" "SMD Multilayer Ceramic Capacitor, 0.1 µF, 50 V, 0402 [1005 Metric], ± 10%, X5R, GRM Series"
			(at 0 0 180)
			(layer "F.Fab")
			(hide yes)
			(effects
				(font
					(size 1.27 1.27)
					(thickness 0.15)
				)
			)
		)
		(property "Author" "Antmicro"
			(at 436.42 308.28 0)
			(layer "F.Fab")
			(hide yes)
			(effects
				(font
					(size 1 1)
					(thickness 0.15)
				)
			)
		)
		(property "Dielectric" "X5R"
			(at 436.42 308.28 0)
			(layer "F.Fab")
			(hide yes)
			(effects
				(font
					(size 1 1)
					(thickness 0.15)
				)
			)
		)
		(property "License" "Apache-2.0"
			(at 436.42 308.28 0)
			(layer "F.Fab")
			(hide yes)
			(effects
				(font
					(size 1 1)
					(thickness 0.15)
				)
			)
		)
		(property "MPN" "GRM155R61H104KE14D"
			(at 436.42 308.28 0)
			(layer "F.Fab")
			(hide yes)
			(effects
				(font
					(size 1 1)
					(thickness 0.15)
				)
			)
		)
		(property "Manufacturer" "Murata"
			(at 436.42 308.28 0)
			(layer "F.Fab")
			(hide yes)
			(effects
				(font
					(size 1 1)
					(thickness 0.15)
				)
			)
		)
		(property "Public" ""
			(at 436.42 308.28 0)
			(layer "F.Fab")
			(hide yes)
			(effects
				(font
					(size 1 1)
					(thickness 0.15)
				)
			)
		)
		(property "Val" "100n"
			(at 436.42 308.28 0)
			(layer "F.Fab")
			(hide yes)
			(effects
				(font
					(size 1 1)
					(thickness 0.15)
				)
			)
		)
		(property "Voltage" "50V"
			(at 436.42 308.28 0)
			(layer "F.Fab")
			(hide yes)
			(effects
				(font
					(size 1 1)
					(thickness 0.15)
				)
			)
		)
		(sheetname "/PCIe/")
		(sheetfile "pcie.kicad_sch")
		(attr smd)
		(fp_rect
			(start -0.925 -0.47)
			(end 0.925 0.47)
			(stroke
				(width 0.05)
				(type default)
			)
			(fill no)
			(layer "F.CrtYd")
		)
		(fp_line
			(start 0.504 0.248)
			(end -0.494 0.248)
			(stroke
				(width 0.15)
				(type solid)
			)
			(layer "F.Fab")
		)
		(fp_line
			(start 0.504 -0.25)
			(end 0.504 0.248)
			(stroke
				(width 0.15)
				(type solid)
			)
			(layer "F.Fab")
		)
		(fp_line
			(start -0.494 0.248)
			(end -0.494 -0.25)
			(stroke
				(width 0.15)
				(type solid)
			)
			(layer "F.Fab")
		)
		(fp_line
			(start -0.494 -0.25)
			(end 0.504 -0.25)
			(stroke
				(width 0.15)
				(type solid)
			)
			(layer "F.Fab")
		)
		(fp_text user "${REFERENCE}"
			(at -0.939 4.599 180)
			(layer "F.Fab")
			(effects
				(font
					(size 0.7 0.7)
					(thickness 0.15)
				)
				(justify left bottom)
			)
		)
		(fp_text user "License: Apache-2.0"
			(at -0.939 5.799 180)
			(layer "F.Fab")
			(effects
				(font
					(size 0.7 0.7)
					(thickness 0.15)
				)
				(justify left bottom)
			)
		)
		(fp_text user "Author: Antmicro"
			(at -0.939 3.399 180)
			(layer "F.Fab")
			(effects
				(font
					(size 0.7 0.7)
					(thickness 0.15)
				)
				(justify left bottom)
			)
		)
		(pad "1" smd roundrect
			(at -0.48 0 180)
			(size 0.59 0.64)
			(layers "F.Cu" "F.Mask" "F.Paste")
			(roundrect_rratio 0.25)
			(net 315 "Net-(U17-CLK1+)")
			(pintype "passive")
		)
		(pad "2" smd roundrect
			(at 0.48 0 180)
			(size 0.59 0.64)
			(layers "F.Cu" "F.Mask" "F.Paste")
			(roundrect_rratio 0.25)
			(net 5 "/Bottom Connector/PCIE.CLK_P")
			(pintype "passive")
		)
	)
)
